# S9S_MB_2U (Grand Teton) — schematic netlist excerpt (pin names and nets, part order shuffled) for the footprints in the layout excerpt that follows; sources: Cadence DE-HDL packaged netlist, KiCad conversion of 03242023_DA0F0TMBIJ0_F0T_Motherboard_J_brd_V01_OCP.brd

R206  Q_RES  1.5K 1% CHIP  pkg 0402LF  page 123 : A = H_CPU1_MEMTRIP_LVC1_R_N ; B = H_CPU1_MEMTRIP_OUT_VT_R_N
R3459  Q_RES  4.7K 5% CHIP  pkg 0402LF  page 150 : A = P3V3_AUX ; B = GPU_NVS_PWR_BRAKE_N

(kicad_pcb
	(version 20260206)
	(generator "pcbnew")
	(generator_version "10.0")
	(general
		(thickness 1.6)
		(legacy_teardrops no)
	)
	(paper "A4")
	(title_block
		(title "03242023_DA0F0TMBIJ0_F0T_Motherboard_J_brd_V01_OCP.brd")
		(comment 1 "Grand Teton / footprints 2837-2838 of 6105")
	)
	(layers
		(0 "F.Cu" signal "TOP")
		(4 "In1.Cu" signal "GND")
		(6 "In2.Cu" signal "IN1")
		(8 "In3.Cu" signal "GND1")
		(10 "In4.Cu" signal "IN2")
		(12 "In5.Cu" signal "GND2")
		(14 "In6.Cu" signal "IN3")
		(16 "In7.Cu" signal "GND3")
		(18 "In8.Cu" signal "VCC")
		(20 "In9.Cu" signal "VCC1")
		(22 "In10.Cu" signal "GND4")
		(24 "In11.Cu" signal "IN4")
		(26 "In12.Cu" signal "GND5")
		(28 "In13.Cu" signal "IN5")
		(30 "In14.Cu" signal "GND6")
		(32 "In15.Cu" signal "IN6")
		(34 "In16.Cu" signal "GND7")
		(2 "B.Cu" signal "BOTTOM")
		(9 "F.Adhes" user "F.Adhesive")
		(11 "B.Adhes" user "B.Adhesive")
		(13 "F.Paste" user "Package Geometry/Pastemask Top")
		(15 "B.Paste" user "Package Geometry/Pastemask Bottom")
		(5 "F.SilkS" user "Ref Des/Silkscreen Top")
		(7 "B.SilkS" user "Ref Des/Silkscreen Bottom")
		(1 "F.Mask" user "Board Geometry/Soldermask Top")
		(3 "B.Mask" user "Board Geometry/Soldermask Bottom")
		(17 "Dwgs.User" user "User.Drawings")
		(19 "Cmts.User" user "User.Comments")
		(21 "Eco1.User" user "User.Eco1")
		(23 "Eco2.User" user "User.Eco2")
		(25 "Edge.Cuts" user "Board Geometry/Outline")
		(27 "Margin" user)
		(31 "F.CrtYd" user "Package Geometry/Place Bound Top")
		(29 "B.CrtYd" user "Package Geometry/Place Bound Bottom")
		(35 "F.Fab" user "Ref Des/Assembly Top")
		(33 "B.Fab" user "Ref Des/Assembly Bottom")
	)
	(footprint ""
		(layer "F.Cu")
		(at 133.53288 -100.167948 90)
		(property "Reference" "R206"
			(at 0 0 90)
			(layer "F.SilkS")
			(hide yes)
			(effects
				(font
					(size 1.27 1.27)
				)
			)
		)
		(property "Value" ""
			(at 0 0 90)
			(layer "F.Fab")
			(effects
				(font
					(size 1.27 1.27)
				)
			)
		)
		(duplicate_pad_numbers_are_jumpers no)
		(fp_line
			(start 0.7874 -0.4064)
			(end 0.7874 0.4064)
			(stroke
				(width 0.1524)
				(type default)
			)
			(layer "F.SilkS")
		)
		(fp_line
			(start -0.7874 -0.4064)
			(end 0.7874 -0.4064)
			(stroke
				(width 0.1524)
				(type default)
			)
			(layer "F.SilkS")
		)
		(fp_line
			(start 0.7874 0.4064)
			(end -0.7874 0.4064)
			(stroke
				(width 0.1524)
				(type default)
			)
			(layer "F.SilkS")
		)
		(fp_line
			(start -0.7874 0.4064)
			(end -0.7874 -0.4064)
			(stroke
				(width 0.1524)
				(type default)
			)
			(layer "F.SilkS")
		)
		(fp_line
			(start -0.12065 -0.305054)
			(end -0.12065 -0.2794)
			(stroke
				(width 0.1)
				(type default)
			)
			(layer "F.Fab")
		)
		(fp_line
			(start -0.67945 -0.305054)
			(end -0.12065 -0.305054)
			(stroke
				(width 0.1)
				(type default)
			)
			(layer "F.Fab")
		)
		(fp_line
			(start 0.67945 -0.3048)
			(end 0.67945 0.3048)
			(stroke
				(width 0.1)
				(type default)
			)
			(layer "F.Fab")
		)
		(fp_line
			(start 0.12065 -0.3048)
			(end 0.67945 -0.3048)
			(stroke
				(width 0.1)
				(type default)
			)
			(layer "F.Fab")
		)
		(fp_line
			(start 0.12065 -0.2794)
			(end 0.12065 -0.3048)
			(stroke
				(width 0.1)
				(type default)
			)
			(layer "F.Fab")
		)
		(fp_line
			(start -0.12065 -0.2794)
			(end 0.12065 -0.2794)
			(stroke
				(width 0.1)
				(type default)
			)
			(layer "F.Fab")
		)
		(fp_line
			(start 0.120396 0.2794)
			(end -0.12065 0.2794)
			(stroke
				(width 0.1)
				(type default)
			)
			(layer "F.Fab")
		)
		(fp_line
			(start -0.12065 0.2794)
			(end -0.12065 0.3048)
			(stroke
				(width 0.1)
				(type default)
			)
			(layer "F.Fab")
		)
		(fp_line
			(start 0.67945 0.3048)
			(end 0.120396 0.3048)
			(stroke
				(width 0.1)
				(type default)
			)
			(layer "F.Fab")
		)
		(fp_line
			(start 0.120396 0.3048)
			(end 0.120396 0.2794)
			(stroke
				(width 0.1)
				(type default)
			)
			(layer "F.Fab")
		)
		(fp_line
			(start -0.12065 0.3048)
			(end -0.67945 0.3048)
			(stroke
				(width 0.1)
				(type default)
			)
			(layer "F.Fab")
		)
		(fp_line
			(start -0.67945 0.3048)
			(end -0.67945 -0.305054)
			(stroke
				(width 0.1)
				(type default)
			)
			(layer "F.Fab")
		)
		(pad "1" smd circle
			(at -0.40005 0 90)
			(size 0 0)
			(layers "F.Cu" "F.Mask" "F.Paste")
			(net "H_CPU1_MEMTRIP_LVC1_R_N")
		)
		(pad "2" smd circle
			(at 0.40005 0 90)
			(size 0 0)
			(layers "F.Cu" "F.Mask" "F.Paste")
			(net "H_CPU1_MEMTRIP_OUT_VT_R_N")
		)
	)
	(footprint ""
		(layer "F.Cu")
		(at 109.580934 -393.14374 180)
		(property "Reference" "R3459"
			(at 0 0 180)
			(layer "F.SilkS")
			(hide yes)
			(effects
				(font
					(size 1.27 1.27)
				)
			)
		)
		(property "Value" ""
			(at 0 0 180)
			(layer "F.Fab")
			(effects
				(font
					(size 1.27 1.27)
				)
			)
		)
		(duplicate_pad_numbers_are_jumpers no)
		(fp_line
			(start 0.7874 0.4064)
			(end -0.7874 0.4064)
			(stroke
				(width 0.1524)
				(type default)
			)
			(layer "F.SilkS")
		)
		(fp_line
			(start 0.7874 -0.4064)
			(end 0.7874 0.4064)
			(stroke
				(width 0.1524)
				(type default)
			)
			(layer "F.SilkS")
		)
		(fp_line
			(start -0.7874 0.4064)
			(end -0.7874 -0.4064)
			(stroke
				(width 0.1524)
				(type default)
			)
			(layer "F.SilkS")
		)
		(fp_line
			(start -0.7874 -0.4064)
			(end 0.7874 -0.4064)
			(stroke
				(width 0.1524)
				(type default)
			)
			(layer "F.SilkS")
		)
		(fp_line
			(start 0.67945 0.3048)
			(end 0.120396 0.3048)
			(stroke
				(width 0.1)
				(type default)
			)
			(layer "F.Fab")
		)
		(fp_line
			(start 0.67945 -0.3048)
			(end 0.67945 0.3048)
			(stroke
				(width 0.1)
				(type default)
			)
			(layer "F.Fab")
		)
		(fp_line
			(start 0.12065 -0.2794)
			(end 0.12065 -0.3048)
			(stroke
				(width 0.1)
				(type default)
			)
			(layer "F.Fab")
		)
		(fp_line
			(start 0.12065 -0.3048)
			(end 0.67945 -0.3048)
			(stroke
				(width 0.1)
				(type default)
			)
			(layer "F.Fab")
		)
		(fp_line
			(start 0.120396 0.3048)
			(end 0.120396 0.2794)
			(stroke
				(width 0.1)
				(type default)
			)
			(layer "F.Fab")
		)
		(fp_line
			(start 0.120396 0.2794)
			(end -0.12065 0.2794)
			(stroke
				(width 0.1)
				(type default)
			)
			(layer "F.Fab")
		)
		(fp_line
			(start -0.12065 0.3048)
			(end -0.67945 0.3048)
			(stroke
				(width 0.1)
				(type default)
			)
			(layer "F.Fab")
		)
		(fp_line
			(start -0.12065 0.2794)
			(end -0.12065 0.3048)
			(stroke
				(width 0.1)
				(type default)
			)
			(layer "F.Fab")
		)
		(fp_line
			(start -0.12065 -0.2794)
			(end 0.12065 -0.2794)
			(stroke
				(width 0.1)
				(type default)
			)
			(layer "F.Fab")
		)
		(fp_line
			(start -0.12065 -0.305054)
			(end -0.12065 -0.2794)
			(stroke
				(width 0.1)
				(type default)
			)
			(layer "F.Fab")
		)
		(fp_line
			(start -0.67945 0.3048)
			(end -0.67945 -0.305054)
			(stroke
				(width 0.1)
				(type default)
			)
			(layer "F.Fab")
		)
		(fp_line
			(start -0.67945 -0.305054)
			(end -0.12065 -0.305054)
			(stroke
				(width 0.1)
				(type default)
			)
			(layer "F.Fab")
		)
		(pad "1" smd circle
			(at -0.40005 0 180)
			(size 0 0)
			(layers "F.Cu" "F.Mask" "F.Paste")
			(net "P3V3_AUX")
		)
		(pad "2" smd circle
			(at 0.40005 0 180)
			(size 0 0)
			(layers "F.Cu" "F.Mask" "F.Paste")
			(net "GPU_NVS_PWR_BRAKE_N")
		)
	)
)
